# S9S_MB_2U (Grand Teton) — schematic netlist excerpt (pin names and nets, part order shuffled) for the footprints in the layout excerpt that follows; sources: Cadence DE-HDL packaged netlist, KiCad conversion of 03242023_DA0F0TMBIJ0_F0T_Motherboard_J_brd_V01_OCP.brd

R273  Q_RES  10K 1% CHIP  pkg 0402LF  page 119 : A = P3V3_AUX ; B = FM_CPU1_PROC_ID0
PR4699  Q_RES  0 5% CHIP  pkg 0402LF  page 300 : A = PVNN_MAIN_CPU1_FB_RC ; B = PVNN_MAIN_CPU1

(kicad_pcb
	(version 20260206)
	(generator "pcbnew")
	(generator_version "10.0")
	(general
		(thickness 1.6)
		(legacy_teardrops no)
	)
	(paper "A4")
	(title_block
		(title "03242023_DA0F0TMBIJ0_F0T_Motherboard_J_brd_V01_OCP.brd")
		(comment 1 "Grand Teton / footprints 3705-3706 of 6105")
	)
	(layers
		(0 "F.Cu" signal "TOP")
		(4 "In1.Cu" signal "GND")
		(6 "In2.Cu" signal "IN1")
		(8 "In3.Cu" signal "GND1")
		(10 "In4.Cu" signal "IN2")
		(12 "In5.Cu" signal "GND2")
		(14 "In6.Cu" signal "IN3")
		(16 "In7.Cu" signal "GND3")
		(18 "In8.Cu" signal "VCC")
		(20 "In9.Cu" signal "VCC1")
		(22 "In10.Cu" signal "GND4")
		(24 "In11.Cu" signal "IN4")
		(26 "In12.Cu" signal "GND5")
		(28 "In13.Cu" signal "IN5")
		(30 "In14.Cu" signal "GND6")
		(32 "In15.Cu" signal "IN6")
		(34 "In16.Cu" signal "GND7")
		(2 "B.Cu" signal "BOTTOM")
		(9 "F.Adhes" user "F.Adhesive")
		(11 "B.Adhes" user "B.Adhesive")
		(13 "F.Paste" user "Package Geometry/Pastemask Top")
		(15 "B.Paste" user "Package Geometry/Pastemask Bottom")
		(5 "F.SilkS" user "Ref Des/Silkscreen Top")
		(7 "B.SilkS" user "Ref Des/Silkscreen Bottom")
		(1 "F.Mask" user "Board Geometry/Soldermask Top")
		(3 "B.Mask" user "Board Geometry/Soldermask Bottom")
		(17 "Dwgs.User" user "User.Drawings")
		(19 "Cmts.User" user "User.Comments")
		(21 "Eco1.User" user "User.Eco1")
		(23 "Eco2.User" user "User.Eco2")
		(25 "Edge.Cuts" user "Board Geometry/Outline")
		(27 "Margin" user)
		(31 "F.CrtYd" user "Package Geometry/Place Bound Top")
		(29 "B.CrtYd" user "Package Geometry/Place Bound Bottom")
		(35 "F.Fab" user "Ref Des/Assembly Top")
		(33 "B.Fab" user "Ref Des/Assembly Bottom")
	)
	(footprint ""
		(layer "F.Cu")
		(at 27.58313 -174.11446)
		(property "Reference" "PR4699"
			(at 0 0 0)
			(layer "F.SilkS")
			(hide yes)
			(effects
				(font
					(size 1.27 1.27)
				)
			)
		)
		(property "Value" ""
			(at 0 0 0)
			(layer "F.Fab")
			(effects
				(font
					(size 1.27 1.27)
				)
			)
		)
		(duplicate_pad_numbers_are_jumpers no)
		(fp_line
			(start -0.7874 -0.4064)
			(end 0.7874 -0.4064)
			(stroke
				(width 0.1524)
				(type default)
			)
			(layer "F.SilkS")
		)
		(fp_line
			(start -0.7874 0.4064)
			(end -0.7874 -0.4064)
			(stroke
				(width 0.1524)
				(type default)
			)
			(layer "F.SilkS")
		)
		(fp_line
			(start 0.7874 -0.4064)
			(end 0.7874 0.4064)
			(stroke
				(width 0.1524)
				(type default)
			)
			(layer "F.SilkS")
		)
		(fp_line
			(start 0.7874 0.4064)
			(end -0.7874 0.4064)
			(stroke
				(width 0.1524)
				(type default)
			)
			(layer "F.SilkS")
		)
		(fp_line
			(start -0.67945 -0.305054)
			(end -0.12065 -0.305054)
			(stroke
				(width 0.1)
				(type default)
			)
			(layer "F.Fab")
		)
		(fp_line
			(start -0.67945 0.3048)
			(end -0.67945 -0.305054)
			(stroke
				(width 0.1)
				(type default)
			)
			(layer "F.Fab")
		)
		(fp_line
			(start -0.12065 -0.305054)
			(end -0.12065 -0.2794)
			(stroke
				(width 0.1)
				(type default)
			)
			(layer "F.Fab")
		)
		(fp_line
			(start -0.12065 -0.2794)
			(end 0.12065 -0.2794)
			(stroke
				(width 0.1)
				(type default)
			)
			(layer "F.Fab")
		)
		(fp_line
			(start -0.12065 0.2794)
			(end -0.12065 0.3048)
			(stroke
				(width 0.1)
				(type default)
			)
			(layer "F.Fab")
		)
		(fp_line
			(start -0.12065 0.3048)
			(end -0.67945 0.3048)
			(stroke
				(width 0.1)
				(type default)
			)
			(layer "F.Fab")
		)
		(fp_line
			(start 0.120396 0.2794)
			(end -0.12065 0.2794)
			(stroke
				(width 0.1)
				(type default)
			)
			(layer "F.Fab")
		)
		(fp_line
			(start 0.120396 0.3048)
			(end 0.120396 0.2794)
			(stroke
				(width 0.1)
				(type default)
			)
			(layer "F.Fab")
		)
		(fp_line
			(start 0.12065 -0.3048)
			(end 0.67945 -0.3048)
			(stroke
				(width 0.1)
				(type default)
			)
			(layer "F.Fab")
		)
		(fp_line
			(start 0.12065 -0.2794)
			(end 0.12065 -0.3048)
			(stroke
				(width 0.1)
				(type default)
			)
			(layer "F.Fab")
		)
		(fp_line
			(start 0.67945 -0.3048)
			(end 0.67945 0.3048)
			(stroke
				(width 0.1)
				(type default)
			)
			(layer "F.Fab")
		)
		(fp_line
			(start 0.67945 0.3048)
			(end 0.120396 0.3048)
			(stroke
				(width 0.1)
				(type default)
			)
			(layer "F.Fab")
		)
		(pad "1" smd circle
			(at -0.40005 0)
			(size 0 0)
			(layers "F.Cu" "F.Mask" "F.Paste")
			(net "PVNN_MAIN_CPU1_FB_RC")
		)
		(pad "2" smd circle
			(at 0.40005 0)
			(size 0 0)
			(layers "F.Cu" "F.Mask" "F.Paste")
			(net "PVNN_MAIN_CPU1")
		)
	)
	(footprint ""
		(layer "F.Cu")
		(at 179.12588 -126.964948 -90)
		(property "Reference" "R273"
			(at 0 0 270)
			(layer "F.SilkS")
			(hide yes)
			(effects
				(font
					(size 1.27 1.27)
				)
			)
		)
		(property "Value" ""
			(at 0 0 270)
			(layer "F.Fab")
			(effects
				(font
					(size 1.27 1.27)
				)
			)
		)
		(duplicate_pad_numbers_are_jumpers no)
		(fp_line
			(start -0.7874 0.4064)
			(end -0.7874 -0.4064)
			(stroke
				(width 0.1524)
				(type default)
			)
			(layer "F.SilkS")
		)
		(fp_line
			(start 0.7874 0.4064)
			(end -0.7874 0.4064)
			(stroke
				(width 0.1524)
				(type default)
			)
			(layer "F.SilkS")
		)
		(fp_line
			(start -0.7874 -0.4064)
			(end 0.7874 -0.4064)
			(stroke
				(width 0.1524)
				(type default)
			)
			(layer "F.SilkS")
		)
		(fp_line
			(start 0.7874 -0.4064)
			(end 0.7874 0.4064)
			(stroke
				(width 0.1524)
				(type default)
			)
			(layer "F.SilkS")
		)
		(fp_line
			(start -0.67945 0.3048)
			(end -0.67945 -0.305054)
			(stroke
				(width 0.1)
				(type default)
			)
			(layer "F.Fab")
		)
		(fp_line
			(start -0.12065 0.3048)
			(end -0.67945 0.3048)
			(stroke
				(width 0.1)
				(type default)
			)
			(layer "F.Fab")
		)
		(fp_line
			(start 0.120396 0.3048)
			(end 0.120396 0.2794)
			(stroke
				(width 0.1)
				(type default)
			)
			(layer "F.Fab")
		)
		(fp_line
			(start 0.67945 0.3048)
			(end 0.120396 0.3048)
			(stroke
				(width 0.1)
				(type default)
			)
			(layer "F.Fab")
		)
		(fp_line
			(start -0.12065 0.2794)
			(end -0.12065 0.3048)
			(stroke
				(width 0.1)
				(type default)
			)
			(layer "F.Fab")
		)
		(fp_line
			(start 0.120396 0.2794)
			(end -0.12065 0.2794)
			(stroke
				(width 0.1)
				(type default)
			)
			(layer "F.Fab")
		)
		(fp_line
			(start -0.12065 -0.2794)
			(end 0.12065 -0.2794)
			(stroke
				(width 0.1)
				(type default)
			)
			(layer "F.Fab")
		)
		(fp_line
			(start 0.12065 -0.2794)
			(end 0.12065 -0.3048)
			(stroke
				(width 0.1)
				(type default)
			)
			(layer "F.Fab")
		)
		(fp_line
			(start 0.12065 -0.3048)
			(end 0.67945 -0.3048)
			(stroke
				(width 0.1)
				(type default)
			)
			(layer "F.Fab")
		)
		(fp_line
			(start 0.67945 -0.3048)
			(end 0.67945 0.3048)
			(stroke
				(width 0.1)
				(type default)
			)
			(layer "F.Fab")
		)
		(fp_line
			(start -0.67945 -0.305054)
			(end -0.12065 -0.305054)
			(stroke
				(width 0.1)
				(type default)
			)
			(layer "F.Fab")
		)
		(fp_line
			(start -0.12065 -0.305054)
			(end -0.12065 -0.2794)
			(stroke
				(width 0.1)
				(type default)
			)
			(layer "F.Fab")
		)
		(pad "1" smd circle
			(at -0.40005 0 270)
			(size 0 0)
			(layers "F.Cu" "F.Mask" "F.Paste")
			(net "P3V3_AUX")
		)
		(pad "2" smd circle
			(at 0.40005 0 270)
			(size 0 0)
			(layers "F.Cu" "F.Mask" "F.Paste")
			(net "FM_CPU1_PROC_ID0")
		)
	)
)
